# TIMECARD (Time Appliance Project (Time Card)) — schematic netlist excerpt (pin names and nets, part order shuffled) for the footprints in the layout excerpt that follows; sources: Cadence DE-HDL packaged netlist, KiCad conversion of R4006-B0001-02_R01.brd

R34  RESISTOR  24KOHM 1%  pkg SMC_0402R_H016  page 32 : \1\ = UNNAMED_516_CAPACITOR_I29_1 ; \2\ = XP5R0V_FB_R_TO_AGND
C137  CAPACITOR  47UF 4V 20%  pkg SMC_0805R_H057  page 14 : \1\ = XP1R0V_FPGA_MGTAVCC ; \2\ = SG

(kicad_pcb
	(version 20260206)
	(generator "pcbnew")
	(generator_version "10.0")
	(general
		(thickness 1.6)
		(legacy_teardrops no)
	)
	(paper "A4")
	(title_block
		(title "timecard-production-celestica-r4006 — R4006-B0001-02_R01.brd")
		(comment 1 "Time Appliance Project (Time Card) / footprints 451-452 of 1113")
	)
	(layers
		(0 "F.Cu" signal "TOP")
		(4 "In1.Cu" signal "L02_GND1")
		(6 "In2.Cu" signal "L03_SIG1")
		(8 "In3.Cu" signal "L04_GND2")
		(10 "In4.Cu" signal "L05_VCC1")
		(12 "In5.Cu" signal "L06_VCC2")
		(14 "In6.Cu" signal "L07_GND3")
		(16 "In7.Cu" signal "L08_SIG2")
		(18 "In8.Cu" signal "L09_GND4")
		(2 "B.Cu" signal "BOTTOM")
		(9 "F.Adhes" user "F.Adhesive")
		(11 "B.Adhes" user "B.Adhesive")
		(13 "F.Paste" user "Package Geometry/Pastemask Top")
		(15 "B.Paste" user "Package Geometry/Pastemask Bottom")
		(5 "F.SilkS" user "Ref Des/Silkscreen Top")
		(7 "B.SilkS" user "Ref Des/Silkscreen Bottom")
		(1 "F.Mask" user "Board Geometry/Soldermask Top")
		(3 "B.Mask" user "Board Geometry/Soldermask Bottom")
		(17 "Dwgs.User" user "User.Drawings")
		(19 "Cmts.User" user "User.Comments")
		(21 "Eco1.User" user "User.Eco1")
		(23 "Eco2.User" user "User.Eco2")
		(25 "Edge.Cuts" user "Board Geometry/Outline")
		(27 "Margin" user)
		(31 "F.CrtYd" user "Package Geometry/Place Bound Top")
		(29 "B.CrtYd" user "Package Geometry/Place Bound Bottom")
		(35 "F.Fab" user "Ref Des/Assembly Top")
		(33 "B.Fab" user "Ref Des/Assembly Bottom")
	)
	(footprint ""
		(layer "F.Cu")
		(at 36.9824 -105.2068)
		(property "Reference" "R34"
			(at -4.0894 -0.92583 0)
			(unlocked yes)
			(layer "F.SilkS")
			(effects
				(font
					(size 0.7874 0.5842)
					(thickness 0.1524)
				)
			)
		)
		(property "Value" "VAL*"
			(at 0.02032 2.13233 0)
			(unlocked yes)
			(layer "F.Fab")
			(hide yes)
			(effects
				(font
					(size 0.7874 0.5842)
					(thickness 0.1524)
				)
			)
		)
		(property "Tolerance" "TOL*"
			(at 0.044704 3.05435 0)
			(unlocked yes)
			(layer "Cmts.User")
			(hide yes)
			(effects
				(font
					(size 0.7874 0.5842)
					(thickness 0.1524)
				)
			)
		)
		(property "User Part Number" "PARTNUM*"
			(at 0.02032 4.024884 0)
			(unlocked yes)
			(layer "Cmts.User")
			(hide yes)
			(effects
				(font
					(size 0.7874 0.5842)
					(thickness 0.1524)
				)
			)
		)
		(property "Device Type" "RESISTOR-G155-02402-01,24KOHM,A"
			(at 0.008382 1.210564 0)
			(unlocked yes)
			(layer "F.Fab")
			(hide yes)
			(effects
				(font
					(size 0.7874 0.5842)
					(thickness 0.1524)
				)
			)
		)
		(duplicate_pad_numbers_are_jumpers no)
		(fp_line
			(start -1.143 -0.5588)
			(end -1.143 0.5588)
			(stroke
				(width 0.1)
				(type default)
			)
			(layer "F.SilkS")
		)
		(fp_line
			(start -1.143 0.5588)
			(end 1.143 0.5588)
			(stroke
				(width 0.1)
				(type default)
			)
			(layer "F.SilkS")
		)
		(fp_line
			(start 1.143 -0.5588)
			(end -1.143 -0.5588)
			(stroke
				(width 0.1)
				(type default)
			)
			(layer "F.SilkS")
		)
		(fp_line
			(start 1.143 0.5588)
			(end 1.143 -0.5588)
			(stroke
				(width 0.1)
				(type default)
			)
			(layer "F.SilkS")
		)
		(fp_poly
			(pts
				(xy -1.143 0.5588) (xy 1.143 0.5588) (xy 1.143 -0.5588) (xy -1.143 -0.5588)
			)
			(stroke
				(width 0)
				(type default)
			)
			(fill no)
			(layer "F.CrtYd")
		)
		(fp_line
			(start -0.508 -0.3048)
			(end -0.508 0.3048)
			(stroke
				(width 0.1)
				(type default)
			)
			(layer "F.Fab")
		)
		(fp_line
			(start -0.508 0.3048)
			(end 0.508 0.3048)
			(stroke
				(width 0.1)
				(type default)
			)
			(layer "F.Fab")
		)
		(fp_line
			(start 0.508 -0.3048)
			(end -0.508 -0.3048)
			(stroke
				(width 0.1)
				(type default)
			)
			(layer "F.Fab")
		)
		(fp_line
			(start 0.508 0.3048)
			(end 0.508 -0.3048)
			(stroke
				(width 0.1)
				(type default)
			)
			(layer "F.Fab")
		)
		(pad "1" smd rect
			(at -0.5334 0)
			(size 0.7112 0.6096)
			(layers "F.Cu" "F.Mask" "F.Paste")
			(net "UNNAMED_516_CAPACITOR_I29_1")
		)
		(pad "2" smd rect
			(at 0.5334 0)
			(size 0.7112 0.6096)
			(layers "F.Cu" "F.Mask" "F.Paste")
			(net "XP5R0V_FB_R_TO_AGND")
		)
		(zone
			(layer "F.Cu")
			(hatch none 0.5)
			(connect_pads
				(clearance 0)
			)
			(min_thickness 0.25)
			(keepout
				(tracks allowed)
				(vias not_allowed)
				(pads allowed)
				(copperpour not_allowed)
				(footprints allowed)
			)
			(placement
				(enabled no)
				(sheetname "")
			)
			(fill
				(thermal_gap 0.5)
				(thermal_bridge_width 0.5)
				(island_removal_mode 0)
			)
			(polygon
				(pts
					(xy 36.9062 -104.902) (xy 37.0586 -104.902) (xy 37.0586 -105.5116) (xy 36.9062 -105.5116)
				)
			)
		)
		(zone
			(layer "F.Cu")
			(hatch none 0.5)
			(connect_pads
				(clearance 0)
			)
			(min_thickness 0.25)
			(keepout
				(tracks not_allowed)
				(vias allowed)
				(pads allowed)
				(copperpour not_allowed)
				(footprints allowed)
			)
			(placement
				(enabled no)
				(sheetname "")
			)
			(fill
				(thermal_gap 0.5)
				(thermal_bridge_width 0.5)
				(island_removal_mode 0)
			)
			(polygon
				(pts
					(xy 36.9062 -104.902) (xy 37.0586 -104.902) (xy 37.0586 -105.5116) (xy 36.9062 -105.5116)
				)
			)
		)
	)
	(footprint ""
		(layer "F.Cu")
		(at 94.107 -41.021 90)
		(property "Reference" "C137"
			(at 0 -1.48463 90)
			(unlocked yes)
			(layer "F.SilkS")
			(effects
				(font
					(size 0.7874 0.5842)
					(thickness 0.1524)
				)
			)
		)
		(property "Value" "VAL*"
			(at 0.0762 3.134106 90)
			(unlocked yes)
			(layer "F.Fab")
			(hide yes)
			(effects
				(font
					(size 0.7874 0.5842)
					(thickness 0.1524)
				)
			)
		)
		(property "Tolerance" "TOL*"
			(at 0.0762 4.048506 90)
			(unlocked yes)
			(layer "Cmts.User")
			(hide yes)
			(effects
				(font
					(size 0.7874 0.5842)
					(thickness 0.1524)
				)
			)
		)
		(property "User Part Number" "PARTNUM*"
			(at 0.1016 5.013706 90)
			(unlocked yes)
			(layer "Cmts.User")
			(hide yes)
			(effects
				(font
					(size 0.7874 0.5842)
					(thickness 0.1524)
				)
			)
		)
		(property "Device Type" "CAPACITOR-G107-0F476-AM,47UF,2A"
			(at 0.0508 2.194306 90)
			(unlocked yes)
			(layer "F.Fab")
			(hide yes)
			(effects
				(font
					(size 0.7874 0.5842)
					(thickness 0.1524)
				)
			)
		)
		(duplicate_pad_numbers_are_jumpers no)
		(fp_line
			(start 1.5748 -0.9398)
			(end -1.5748 -0.9398)
			(stroke
				(width 0.1)
				(type default)
			)
			(layer "F.SilkS")
		)
		(fp_line
			(start -1.5748 -0.9398)
			(end -1.5748 0.9398)
			(stroke
				(width 0.1)
				(type default)
			)
			(layer "F.SilkS")
		)
		(fp_line
			(start 1.5748 0.9398)
			(end 1.5748 -0.9398)
			(stroke
				(width 0.1)
				(type default)
			)
			(layer "F.SilkS")
		)
		(fp_line
			(start -1.5748 0.9398)
			(end 1.5748 0.9398)
			(stroke
				(width 0.1)
				(type default)
			)
			(layer "F.SilkS")
		)
		(fp_rect
			(start 1.5748 -0.9398)
			(end -1.5748 0.9398)
			(stroke
				(width 0)
				(type default)
			)
			(fill no)
			(layer "F.CrtYd")
		)
		(fp_line
			(start 1.016 -0.635)
			(end -1.016 -0.635)
			(stroke
				(width 0.1)
				(type default)
			)
			(layer "F.Fab")
		)
		(fp_line
			(start -1.016 -0.635)
			(end -1.016 0.635)
			(stroke
				(width 0.1)
				(type default)
			)
			(layer "F.Fab")
		)
		(fp_line
			(start 1.016 0.635)
			(end 1.016 -0.635)
			(stroke
				(width 0.1)
				(type default)
			)
			(layer "F.Fab")
		)
		(fp_line
			(start -1.016 0.635)
			(end 1.016 0.635)
			(stroke
				(width 0.1)
				(type default)
			)
			(layer "F.Fab")
		)
		(pad "1" smd rect
			(at -0.8382 0 90)
			(size 0.9652 1.3716)
			(layers "F.Cu" "F.Mask" "F.Paste")
			(net "XP1R0V_FPGA_MGTAVCC")
		)
		(pad "2" smd rect
			(at 0.8382 0 90)
			(size 0.9652 1.3716)
			(layers "F.Cu" "F.Mask" "F.Paste")
			(net "SG")
		)
		(zone
			(layer "F.Cu")
			(hatch none 0.5)
			(connect_pads
				(clearance 0)
			)
			(min_thickness 0.25)
			(keepout
				(tracks allowed)
				(vias not_allowed)
				(pads allowed)
				(copperpour not_allowed)
				(footprints allowed)
			)
			(placement
				(enabled no)
				(sheetname "")
			)
			(fill
				(thermal_gap 0.5)
				(thermal_bridge_width 0.5)
				(island_removal_mode 0)
			)
			(polygon
				(pts
					(xy 93.472 -41.2496) (xy 93.472 -40.7924) (xy 94.742 -40.7924) (xy 94.742 -41.2496)
				)
			)
		)
	)
)
